# S9S_MB_2U (Grand Teton) — schematic netlist excerpt (pin names and nets, part order shuffled) for the footprints in the layout excerpt that follows; sources: Cadence DE-HDL packaged netlist, KiCad conversion of 03242023_DA0F0TMBIJ0_F0T_Motherboard_J_brd_V01_OCP.brd

PR1766  Q_RES  3.3 1% CHIP  pkg 0402LF  page 285 : A = SW_PVCCIN_CPU1_BOOT2 ; B = SW_PVCCIN_CPU1_BOOT2_R
R2580  Q_RES  0 5% CHIP  pkg 0402LF  page 296 : A = SVID_ALERT1_CPU1_R_N ; B = SVID_ALERT_PVCCD_HV_CPU1_R

(kicad_pcb
	(version 20260206)
	(generator "pcbnew")
	(generator_version "10.0")
	(general
		(thickness 1.6)
		(legacy_teardrops no)
	)
	(paper "A4")
	(title_block
		(title "03242023_DA0F0TMBIJ0_F0T_Motherboard_J_brd_V01_OCP.brd")
		(comment 1 "Grand Teton / footprints 2664-2665 of 6105")
	)
	(layers
		(0 "F.Cu" signal "TOP")
		(4 "In1.Cu" signal "GND")
		(6 "In2.Cu" signal "IN1")
		(8 "In3.Cu" signal "GND1")
		(10 "In4.Cu" signal "IN2")
		(12 "In5.Cu" signal "GND2")
		(14 "In6.Cu" signal "IN3")
		(16 "In7.Cu" signal "GND3")
		(18 "In8.Cu" signal "VCC")
		(20 "In9.Cu" signal "VCC1")
		(22 "In10.Cu" signal "GND4")
		(24 "In11.Cu" signal "IN4")
		(26 "In12.Cu" signal "GND5")
		(28 "In13.Cu" signal "IN5")
		(30 "In14.Cu" signal "GND6")
		(32 "In15.Cu" signal "IN6")
		(34 "In16.Cu" signal "GND7")
		(2 "B.Cu" signal "BOTTOM")
		(9 "F.Adhes" user "F.Adhesive")
		(11 "B.Adhes" user "B.Adhesive")
		(13 "F.Paste" user "Package Geometry/Pastemask Top")
		(15 "B.Paste" user "Package Geometry/Pastemask Bottom")
		(5 "F.SilkS" user "Ref Des/Silkscreen Top")
		(7 "B.SilkS" user "Ref Des/Silkscreen Bottom")
		(1 "F.Mask" user "Board Geometry/Soldermask Top")
		(3 "B.Mask" user "Board Geometry/Soldermask Bottom")
		(17 "Dwgs.User" user "User.Drawings")
		(19 "Cmts.User" user "User.Comments")
		(21 "Eco1.User" user "User.Eco1")
		(23 "Eco2.User" user "User.Eco2")
		(25 "Edge.Cuts" user "Board Geometry/Outline")
		(27 "Margin" user)
		(31 "F.CrtYd" user "Package Geometry/Place Bound Top")
		(29 "B.CrtYd" user "Package Geometry/Place Bound Bottom")
		(35 "F.Fab" user "Ref Des/Assembly Top")
		(33 "B.Fab" user "Ref Des/Assembly Bottom")
	)
	(footprint ""
		(layer "F.Cu")
		(at 22.13356 -163.719256)
		(property "Reference" "R2580"
			(at 0 0 0)
			(layer "F.SilkS")
			(hide yes)
			(effects
				(font
					(size 1.27 1.27)
				)
			)
		)
		(property "Value" ""
			(at 0 0 0)
			(layer "F.Fab")
			(effects
				(font
					(size 1.27 1.27)
				)
			)
		)
		(duplicate_pad_numbers_are_jumpers no)
		(fp_line
			(start -0.7874 -0.4064)
			(end 0.7874 -0.4064)
			(stroke
				(width 0.1524)
				(type default)
			)
			(layer "F.SilkS")
		)
		(fp_line
			(start -0.7874 0.4064)
			(end -0.7874 -0.4064)
			(stroke
				(width 0.1524)
				(type default)
			)
			(layer "F.SilkS")
		)
		(fp_line
			(start 0.7874 -0.4064)
			(end 0.7874 0.4064)
			(stroke
				(width 0.1524)
				(type default)
			)
			(layer "F.SilkS")
		)
		(fp_line
			(start 0.7874 0.4064)
			(end -0.7874 0.4064)
			(stroke
				(width 0.1524)
				(type default)
			)
			(layer "F.SilkS")
		)
		(fp_line
			(start -0.67945 -0.305054)
			(end -0.12065 -0.305054)
			(stroke
				(width 0.1)
				(type default)
			)
			(layer "F.Fab")
		)
		(fp_line
			(start -0.67945 0.3048)
			(end -0.67945 -0.305054)
			(stroke
				(width 0.1)
				(type default)
			)
			(layer "F.Fab")
		)
		(fp_line
			(start -0.12065 -0.305054)
			(end -0.12065 -0.2794)
			(stroke
				(width 0.1)
				(type default)
			)
			(layer "F.Fab")
		)
		(fp_line
			(start -0.12065 -0.2794)
			(end 0.12065 -0.2794)
			(stroke
				(width 0.1)
				(type default)
			)
			(layer "F.Fab")
		)
		(fp_line
			(start -0.12065 0.2794)
			(end -0.12065 0.3048)
			(stroke
				(width 0.1)
				(type default)
			)
			(layer "F.Fab")
		)
		(fp_line
			(start -0.12065 0.3048)
			(end -0.67945 0.3048)
			(stroke
				(width 0.1)
				(type default)
			)
			(layer "F.Fab")
		)
		(fp_line
			(start 0.120396 0.2794)
			(end -0.12065 0.2794)
			(stroke
				(width 0.1)
				(type default)
			)
			(layer "F.Fab")
		)
		(fp_line
			(start 0.120396 0.3048)
			(end 0.120396 0.2794)
			(stroke
				(width 0.1)
				(type default)
			)
			(layer "F.Fab")
		)
		(fp_line
			(start 0.12065 -0.3048)
			(end 0.67945 -0.3048)
			(stroke
				(width 0.1)
				(type default)
			)
			(layer "F.Fab")
		)
		(fp_line
			(start 0.12065 -0.2794)
			(end 0.12065 -0.3048)
			(stroke
				(width 0.1)
				(type default)
			)
			(layer "F.Fab")
		)
		(fp_line
			(start 0.67945 -0.3048)
			(end 0.67945 0.3048)
			(stroke
				(width 0.1)
				(type default)
			)
			(layer "F.Fab")
		)
		(fp_line
			(start 0.67945 0.3048)
			(end 0.120396 0.3048)
			(stroke
				(width 0.1)
				(type default)
			)
			(layer "F.Fab")
		)
		(pad "1" smd circle
			(at -0.40005 0)
			(size 0 0)
			(layers "F.Cu" "F.Mask" "F.Paste")
			(net "SVID_ALERT1_CPU1_R_N")
		)
		(pad "2" smd circle
			(at 0.40005 0)
			(size 0 0)
			(layers "F.Cu" "F.Mask" "F.Paste")
			(net "SVID_ALERT_PVCCD_HV_CPU1_R")
		)
	)
	(footprint ""
		(layer "F.Cu")
		(at 105.944416 -338.180172 90)
		(property "Reference" "PR1766"
			(at 0 0 90)
			(layer "F.SilkS")
			(hide yes)
			(effects
				(font
					(size 1.27 1.27)
				)
			)
		)
		(property "Value" ""
			(at 0 0 90)
			(layer "F.Fab")
			(effects
				(font
					(size 1.27 1.27)
				)
			)
		)
		(duplicate_pad_numbers_are_jumpers no)
		(fp_line
			(start 0.7874 -0.4064)
			(end 0.7874 0.4064)
			(stroke
				(width 0.1524)
				(type default)
			)
			(layer "F.SilkS")
		)
		(fp_line
			(start -0.7874 -0.4064)
			(end 0.7874 -0.4064)
			(stroke
				(width 0.1524)
				(type default)
			)
			(layer "F.SilkS")
		)
		(fp_line
			(start 0.7874 0.4064)
			(end -0.7874 0.4064)
			(stroke
				(width 0.1524)
				(type default)
			)
			(layer "F.SilkS")
		)
		(fp_line
			(start -0.7874 0.4064)
			(end -0.7874 -0.4064)
			(stroke
				(width 0.1524)
				(type default)
			)
			(layer "F.SilkS")
		)
		(fp_line
			(start -0.12065 -0.305054)
			(end -0.12065 -0.2794)
			(stroke
				(width 0.1)
				(type default)
			)
			(layer "F.Fab")
		)
		(fp_line
			(start -0.67945 -0.305054)
			(end -0.12065 -0.305054)
			(stroke
				(width 0.1)
				(type default)
			)
			(layer "F.Fab")
		)
		(fp_line
			(start 0.67945 -0.3048)
			(end 0.67945 0.3048)
			(stroke
				(width 0.1)
				(type default)
			)
			(layer "F.Fab")
		)
		(fp_line
			(start 0.12065 -0.3048)
			(end 0.67945 -0.3048)
			(stroke
				(width 0.1)
				(type default)
			)
			(layer "F.Fab")
		)
		(fp_line
			(start 0.12065 -0.2794)
			(end 0.12065 -0.3048)
			(stroke
				(width 0.1)
				(type default)
			)
			(layer "F.Fab")
		)
		(fp_line
			(start -0.12065 -0.2794)
			(end 0.12065 -0.2794)
			(stroke
				(width 0.1)
				(type default)
			)
			(layer "F.Fab")
		)
		(fp_line
			(start 0.120396 0.2794)
			(end -0.12065 0.2794)
			(stroke
				(width 0.1)
				(type default)
			)
			(layer "F.Fab")
		)
		(fp_line
			(start -0.12065 0.2794)
			(end -0.12065 0.3048)
			(stroke
				(width 0.1)
				(type default)
			)
			(layer "F.Fab")
		)
		(fp_line
			(start 0.67945 0.3048)
			(end 0.120396 0.3048)
			(stroke
				(width 0.1)
				(type default)
			)
			(layer "F.Fab")
		)
		(fp_line
			(start 0.120396 0.3048)
			(end 0.120396 0.2794)
			(stroke
				(width 0.1)
				(type default)
			)
			(layer "F.Fab")
		)
		(fp_line
			(start -0.12065 0.3048)
			(end -0.67945 0.3048)
			(stroke
				(width 0.1)
				(type default)
			)
			(layer "F.Fab")
		)
		(fp_line
			(start -0.67945 0.3048)
			(end -0.67945 -0.305054)
			(stroke
				(width 0.1)
				(type default)
			)
			(layer "F.Fab")
		)
		(pad "1" smd circle
			(at -0.40005 0 90)
			(size 0 0)
			(layers "F.Cu" "F.Mask" "F.Paste")
			(net "SW_PVCCIN_CPU1_BOOT2")
		)
		(pad "2" smd circle
			(at 0.40005 0 90)
			(size 0 0)
			(layers "F.Cu" "F.Mask" "F.Paste")
			(net "SW_PVCCIN_CPU1_BOOT2_R")
		)
	)
)
